FILE_TYPE=LIBRARY_PARTS;
primitive 'CONN12_G98257001','CONN12_G98257001_THMT';
  pin
    'A1':
      PIN_NUMBER='(A1)';
      BIDIRECTIONAL='TRUE';
      INPUT_LOAD='(-0.01,0.01)';
      OUTPUT_LOAD='(1.0,-1.0)';
    'A2':
      PIN_NUMBER='(A2)';
      BIDIRECTIONAL='TRUE';
      INPUT_LOAD='(-0.01,0.01)';
      OUTPUT_LOAD='(1.0,-1.0)';
    'A3':
      PIN_NUMBER='(A3)';
      BIDIRECTIONAL='TRUE';
      INPUT_LOAD='(-0.01,0.01)';
      OUTPUT_LOAD='(1.0,-1.0)';
    'B1':
      PIN_NUMBER='(B1)';
      BIDIRECTIONAL='TRUE';
      INPUT_LOAD='(-0.01,0.01)';
      OUTPUT_LOAD='(1.0,-1.0)';
    'B2':
      PIN_NUMBER='(B2)';
      BIDIRECTIONAL='TRUE';
      INPUT_LOAD='(-0.01,0.01)';
      OUTPUT_LOAD='(1.0,-1.0)';
    'B3':
      PIN_NUMBER='(B3)';
      BIDIRECTIONAL='TRUE';
      INPUT_LOAD='(-0.01,0.01)';
      OUTPUT_LOAD='(1.0,-1.0)';
    'C1':
      PIN_NUMBER='(C1)';
      BIDIRECTIONAL='TRUE';
      INPUT_LOAD='(-0.01,0.01)';
      OUTPUT_LOAD='(1.0,-1.0)';
    'C2':
      PIN_NUMBER='(C2)';
      BIDIRECTIONAL='TRUE';
      INPUT_LOAD='(-0.01,0.01)';
      OUTPUT_LOAD='(1.0,-1.0)';
    'C3':
      PIN_NUMBER='(C3)';
      BIDIRECTIONAL='TRUE';
      INPUT_LOAD='(-0.01,0.01)';
      OUTPUT_LOAD='(1.0,-1.0)';
    'D1':
      PIN_NUMBER='(D1)';
      BIDIRECTIONAL='TRUE';
      INPUT_LOAD='(-0.01,0.01)';
      OUTPUT_LOAD='(1.0,-1.0)';
    'D2':
      PIN_NUMBER='(D2)';
      BIDIRECTIONAL='TRUE';
      INPUT_LOAD='(-0.01,0.01)';
      OUTPUT_LOAD='(1.0,-1.0)';
    'D3':
      PIN_NUMBER='(D3)';
      BIDIRECTIONAL='TRUE';
      INPUT_LOAD='(-0.01,0.01)';
      OUTPUT_LOAD='(1.0,-1.0)';
  end_pin;
  body
    PART_NAME='CONN12_G98257001';
    BODY_NAME='CONN12_G98257001';
    PHYS_DES_PREFIX='J';
  end_body;
end_primitive;

END.
